# S9S_MB_2U (Grand Teton) — schematic netlist excerpt (pin names and nets, part order shuffled) for the footprints in the layout excerpt that follows; sources: Cadence DE-HDL packaged netlist, KiCad conversion of 03242023_DA0F0TMBIJ0_F0T_Motherboard_J_brd_V01_OCP.brd

J6  SCONN288_ADR50017P087CC  SCONN288_ADR50017-P087CC IO  pkg DDR288S_1-1VXB  page 87
  VIN_BULK0  = P12V_S3_AUX_CPU0_NVDIMM
  RFU0  = TP_CHC_CPU0_DIMM2_FRU_0
  VIN_MGMT  = P3V3_AUX
  HSCL  = I3C_SPD_DDRABCD_CPU0_LVC1_SCL_5
  HSDA  = I3C_SPD_DDRABCD_CPU0_LVC1_SDA
  VSS0  = GND
  DQ0_A  = M_C_CPU0_SA_DQ<0>
  VSS1  = GND
  DQ1_A  = M_C_CPU0_SA_DQ<1>
  VSS2  = GND
  DQS0_A_T  = M_C_CPU0_SA_DQS_DP<0>
  DQS0_A_C  = M_C_CPU0_SA_DQS_DN<0>
  VSS3  = GND
  DQ4_A  = M_C_CPU0_SA_DQ<4>
  VSS4  = GND
  DQ5_A  = M_C_CPU0_SA_DQ<5>
  VSS5  = GND
  DQ8_A  = M_C_CPU0_SA_DQ<8>
  VSS6  = GND
  DQ9_A  = M_C_CPU0_SA_DQ<9>
  VSS7  = GND
  DQS1_A_T  = M_C_CPU0_SA_DQS_DP<1>
  DQS1_A_C  = M_C_CPU0_SA_DQS_DN<1>
  VSS8  = GND
  DQ12_A  = M_C_CPU0_SA_DQ<12>
  VSS9  = GND
  DQ13_A  = M_C_CPU0_SA_DQ<13>
  VSS10  = GND
  DQ16_A  = M_C_CPU0_SA_DQ<16>
  VSS11  = GND
  DQ17_A  = M_C_CPU0_SA_DQ<17>
  VSS12  = GND
  DQS2_A_T  = M_C_CPU0_SA_DQS_DP<2>
  DQS2_A_C  = M_C_CPU0_SA_DQS_DN<2>
  VSS13  = GND
  DQ20_A  = M_C_CPU0_SA_DQ<20>
  VSS14  = GND
  DQ21_A  = M_C_CPU0_SA_DQ<21>
  VSS15  = GND
  DQ24_A  = M_C_CPU0_SA_DQ<24>
  VSS16  = GND
  DQ25_A  = M_C_CPU0_SA_DQ<25>
  VSS17  = GND
  DQS3_A_T  = M_C_CPU0_SA_DQS_DP<3>
  DQS3_A_C  = M_C_CPU0_SA_DQS_DN<3>
  VSS18  = GND
  DQ28_A  = M_C_CPU0_SA_DQ<28>
  VSS19  = GND
  DQ29_A  = M_C_CPU0_SA_DQ<29>
  VSS20  = GND
  CB0_A  = M_C_CPU0_SA_CB<0>
  VSS21  = GND
  CB1_A  = M_C_CPU0_SA_CB<1>
  VSS22  = GND
  DQS4_A_T  = M_C_CPU0_SA_DQS_DP<4>
  DQS4_A_C  = M_C_CPU0_SA_DQS_DN<4>
  VSS23  = GND
  CB4_A  = M_C_CPU0_SA_CB<4>
  VSS24  = GND
  CB5_A  = M_C_CPU0_SA_CB<5>
  VSS25  = GND
  ALERT_N  = M_C_CPU0_ALERT_N
  VSS26  = GND
  CS0_A_N  = M_C_CPU0_SA_CS_N<2>
  VSS27  = GND
  CA0_A  = M_C_CPU0_SA_CA<0>
  VSS28  = GND
  CA2_A  = M_C_CPU0_SA_CA<2>
  VSS29  = GND
  CA4_A  = M_C_CPU0_SA_CA<4>
  VSS30  = GND
  CA6_A  = M_C_CPU0_SA_CA<6>
  VSS31  = GND
  PAR_A  = M_C_CPU0_SA_PAR
  VSS32  = GND
  CA0_B  = M_C_CPU0_SB_CA<0>
  VSS33  = GND
  CA2_B  = M_C_CPU0_SB_CA<2>
  VSS34  = GND
  CA4_B  = M_C_CPU0_SB_CA<4>
  VSS35  = GND
  CA6_B  = M_C_CPU0_SB_CA<6>
  VSS36  = GND
  CS0_B_N  = M_C_CPU0_SB_CS_N<2>
  VSS37  = GND
  \lbd||rsp_a_n\  = M_C_CPU0_SA_RSP<1>
  \lbs||rsp_b_n\  = M_C_CPU0_SB_RSP<1>
  VSS38  = GND
  CB4_B  = M_C_CPU0_SB_CB<4>
  VSS39  = GND
  CB5_B  = M_C_CPU0_SB_CB<5>
  VSS40  = GND
  \dqs9_b_t||tdqs9_b_t||dbi4_b_n\  = M_C_CPU0_SB_DQS_DP<9>
  \dqs9_b_c||tdqs9_b_c\  = M_C_CPU0_SB_DQS_DN<9>
  VSS41  = GND
  CB0_B  = M_C_CPU0_SB_CB<0>
  VSS42  = GND
  CB1_B  = M_C_CPU0_SB_CB<1>
  VSS43  = GND
  DQ0_B  = M_C_CPU0_SB_DQ<0>
  VSS44  = GND
  DQ1_B  = M_C_CPU0_SB_DQ<1>
  VSS45  = GND
  DQS0_B_T  = M_C_CPU0_SB_DQS_DP<0>
  DQS0_B_C  = M_C_CPU0_SB_DQS_DN<0>
  VSS46  = GND
  DQ4_B  = M_C_CPU0_SB_DQ<4>
  VSS47  = GND
  DQ5_B  = M_C_CPU0_SB_DQ<5>
  VSS48  = GND
  DQ8_B  = M_C_CPU0_SB_DQ<8>
  VSS49  = GND
  DQ9_B  = M_C_CPU0_SB_DQ<9>
  VSS50  = GND
  DQS1_B_T  = M_C_CPU0_SB_DQS_DP<1>
  DQS1_B_C  = M_C_CPU0_SB_DQS_DN<1>
  VSS51  = GND
  DQ12_B  = M_C_CPU0_SB_DQ<12>
  VSS52  = GND
  DQ13_B  = M_C_CPU0_SB_DQ<13>
  VSS53  = GND
  DQ16_B  = M_C_CPU0_SB_DQ<16>
  VSS54  = GND
  DQ17_B  = M_C_CPU0_SB_DQ<17>
  VSS55  = GND
  DQS2_B_T  = M_C_CPU0_SB_DQS_DP<2>
  DQS2_B_C  = M_C_CPU0_SB_DQS_DN<2>
  VSS56  = GND
  DQ20_B  = M_C_CPU0_SB_DQ<20>
  VSS57  = GND
  DQ21_B  = M_C_CPU0_SB_DQ<21>
  VSS58  = GND
  DQ24_B  = M_C_CPU0_SB_DQ<24>
  VSS59  = GND
  DQ25_B  = M_C_CPU0_SB_DQ<25>
  VSS60  = GND
  DQS3_B_T  = M_C_CPU0_SB_DQS_DP<3>
  DQS3_B_C  = M_C_CPU0_SB_DQS_DN<3>
  VSS61  = GND
  DQ28_B  = M_C_CPU0_SB_DQ<28>
  VSS62  = GND
  DQ29_B  = M_C_CPU0_SB_DQ<29>
  VSS63  = GND
  RFU1  = TP_CHC_CPU0_DIMM2_FRU_1
  VIN_BULK1  = P12V_S3_AUX_CPU0_NVDIMM
  VIN_BULK2  = P12V_S3_AUX_CPU0_NVDIMM
  \pwr_good||fail_n\  = PWRGD_CHC_CPU0_DIMM2
  HSA  = PD_CHC_CPU0_DIMM2_SAA
  RFU2  = TP_CHC_CPU0_DIMM2_FRU_2
  RFU3  = TP_CHC_CPU0_DIMM2_FRU_3
  VSS64  = GND
  DQ2_A  = M_C_CPU0_SA_DQ<2>
  VSS65  = GND
  DQ3_A  = M_C_CPU0_SA_DQ<3>
  VSS66  = GND
  \dqs5_a_c||tdqs5_a_c||dqs5_a_t||tdqs5_a_t\  = M_C_CPU0_SA_DQS_DN<5>
  \dqs5_a_t||tdqs5_a_t\  = M_C_CPU0_SA_DQS_DP<5>
  VSS67  = GND
  DQ6_A  = M_C_CPU0_SA_DQ<6>
  VSS68  = GND
  DQ7_A  = M_C_CPU0_SA_DQ<7>
  VSS69  = GND
  DQ10_A  = M_C_CPU0_SA_DQ<10>
  VSS70  = GND
  DQ11_A  = M_C_CPU0_SA_DQ<11>
  VSS71  = GND
  \dqs6_a_c||tdqs6_a_c||dqs6_a_t||tdqs6_a_t\  = M_C_CPU0_SA_DQS_DN<6>
  \dqs6_a_t||tdqs6_a_t\  = M_C_CPU0_SA_DQS_DP<6>
  VSS72  = GND
  DQ14_A  = M_C_CPU0_SA_DQ<14>
  VSS73  = GND
  DQ15_A  = M_C_CPU0_SA_DQ<15>
  VSS74  = GND
  DQ18_A  = M_C_CPU0_SA_DQ<18>
  VSS75  = GND
  DQ19_A  = M_C_CPU0_SA_DQ<19>
  VSS76  = GND
  \dqs7_a_c||tdqs7_a_c\  = M_C_CPU0_SA_DQS_DN<7>
  \dqs7_a_t||tdqs7_a_t\  = M_C_CPU0_SA_DQS_DP<7>
  VSS77  = GND
  DQ22_A  = M_C_CPU0_SA_DQ<22>
  VSS78  = GND
  DQ23_A  = M_C_CPU0_SA_DQ<23>
  VSS79  = GND
  DQ26_A  = M_C_CPU0_SA_DQ<26>
  VSS80  = GND
  DQ27_A  = M_C_CPU0_SA_DQ<27>
  VSS81  = GND
  \dqs8_a_c||tdqs8_a_c\  = M_C_CPU0_SA_DQS_DN<8>
  \dqs8_a_t||tdqs8_a_t\  = M_C_CPU0_SA_DQS_DP<8>
  VSS82  = GND
  DQ30_A  = M_C_CPU0_SA_DQ<30>
  VSS83  = GND
  DQ31_A  = M_C_CPU0_SA_DQ<31>
  VSS84  = GND
  CB2_A  = M_C_CPU0_SA_CB<2>
  VSS85  = GND
  CB3_A  = M_C_CPU0_SA_CB<3>
  VSS86  = GND
  \dqs9_a_c||tdqs9_a_c\  = M_C_CPU0_SA_DQS_DN<9>
  \dqs9_a_t||tdqs9_a_t\  = M_C_CPU0_SA_DQS_DP<9>
  VSS87  = GND
  CB6_A  = M_C_CPU0_SA_CB<6>
  VSS88  = GND
  CB7_A  = M_C_CPU0_SA_CB<7>
  VSS89  = GND
  RESET_N  = RST_M_CD_CPU0_FPGA_N
  VSS90  = GND
  CS1_A_N  = M_C_CPU0_SA_CS_N<3>
  VSS91  = GND
  CA1_A  = M_C_CPU0_SA_CA<1>
  VSS92  = GND
  CA3_A  = M_C_CPU0_SA_CA<3>
  VSS93  = GND
  CA5_A  = M_C_CPU0_SA_CA<5>
  VSS94  = GND
  CK_T  = M_C_CPU0_CLK_DP<1>
  CK_C  = M_C_CPU0_CLK_DN<1>
  VSS95  = GND
  RFU4  = TP_CHC_CPU0_DIMM2_FRU_4
  CA1_B  = M_C_CPU0_SB_CA<1>
  VSS96  = GND
  CA3_B  = M_C_CPU0_SB_CA<3>
  VSS97  = GND
  CA5_B  = M_C_CPU0_SB_CA<5>
  VSS98  = GND
  PAR_B  = M_C_CPU0_SB_PAR
  VSS99  = GND
  CS1_B_N  = M_C_CPU0_SB_CS_N<3>
  VSS100  = GND
  RFU5  = TP_CHC_CPU0_DIMM2_FRU_5
  RFU6  = TP_CHC_CPU0_DIMM2_FRU_6
  VSS101  = GND
  CB6_B  = M_C_CPU0_SB_CB<6>
  VSS102  = GND
  CB7_B  = M_C_CPU0_SB_CB<7>
  VSS103  = GND
  DQS4_B_C  = M_C_CPU0_SB_DQS_DN<4>
  DQS4_B_T  = M_C_CPU0_SB_DQS_DP<4>
  VSS104  = GND
  CB2_B  = M_C_CPU0_SB_CB<2>
  VSS105  = GND
  CB3_B  = M_C_CPU0_SB_CB<3>
  VSS106  = GND
  DQ2_B  = M_C_CPU0_SB_DQ<2>
  VSS107  = GND
  DQ3_B  = M_C_CPU0_SB_DQ<3>
  VSS108  = GND
  \dqs5_b_c||tdqs5_b_c\  = M_C_CPU0_SB_DQS_DN<5>
  \dqs5_b_t||tdqs5_b_t\  = M_C_CPU0_SB_DQS_DP<5>
  VSS109  = GND
  DQ6_B  = M_C_CPU0_SB_DQ<6>
  VSS110  = GND
  DQ7_B  = M_C_CPU0_SB_DQ<7>
  VSS111  = GND
  DQ10_B  = M_C_CPU0_SB_DQ<10>
  VSS112  = GND
  DQ11_B  = M_C_CPU0_SB_DQ<11>
  VSS113  = GND
  \dqs6_b_c||tdqs6_b_c\  = M_C_CPU0_SB_DQS_DN<6>
  \dqs6_b_t||tdqs6_b_t\  = M_C_CPU0_SB_DQS_DP<6>
  VSS114  = GND
  DQ14_B  = M_C_CPU0_SB_DQ<14>
  VSS115  = GND
  DQ15_B  = M_C_CPU0_SB_DQ<15>
  VSS116  = GND
  DQ18_B  = M_C_CPU0_SB_DQ<18>
  VSS117  = GND
  DQ19_B  = M_C_CPU0_SB_DQ<19>
  VSS118  = GND
  \dqs7_b_c||tdqs7_b_c\  = M_C_CPU0_SB_DQS_DN<7>
  \dqs7_b_t||tdqs7_b_t\  = M_C_CPU0_SB_DQS_DP<7>
  VSS119  = GND
  DQ22_B  = M_C_CPU0_SB_DQ<22>
  VSS120  = GND
  DQ23_B  = M_C_CPU0_SB_DQ<23>
  VSS121  = GND
  DQ26_B  = M_C_CPU0_SB_DQ<26>
  VSS122  = GND
  DQ27_B  = M_C_CPU0_SB_DQ<27>
  VSS123  = GND
  \dqs8_b_c||tdqs8_b_c\  = M_C_CPU0_SB_DQS_DN<8>
  \dqs8_b_t||tdqs8_b_t\  = M_C_CPU0_SB_DQS_DP<8>
  VSS124  = GND
  DQ30_B  = M_C_CPU0_SB_DQ<30>
  VSS125  = GND
  DQ31_B  = M_C_CPU0_SB_DQ<31>
  VSS126  = GND
  G1  = GND
  G2  = GND
  G3  = GND

(kicad_pcb
	(version 20260206)
	(generator "pcbnew")
	(generator_version "10.0")
	(general
		(thickness 1.6)
		(legacy_teardrops no)
	)
	(paper "A4")
	(title_block
		(title "03242023_DA0F0TMBIJ0_F0T_Motherboard_J_brd_V01_OCP.brd")
		(comment 1 "Grand Teton / footprint 3553 of 6105 (J6), pads 92-137 of 291")
	)
	(layers
		(0 "F.Cu" signal "TOP")
		(4 "In1.Cu" signal "GND")
		(6 "In2.Cu" signal "IN1")
		(8 "In3.Cu" signal "GND1")
		(10 "In4.Cu" signal "IN2")
		(12 "In5.Cu" signal "GND2")
		(14 "In6.Cu" signal "IN3")
		(16 "In7.Cu" signal "GND3")
		(18 "In8.Cu" signal "VCC")
		(20 "In9.Cu" signal "VCC1")
		(22 "In10.Cu" signal "GND4")
		(24 "In11.Cu" signal "IN4")
		(26 "In12.Cu" signal "GND5")
		(28 "In13.Cu" signal "IN5")
		(30 "In14.Cu" signal "GND6")
		(32 "In15.Cu" signal "IN6")
		(34 "In16.Cu" signal "GND7")
		(2 "B.Cu" signal "BOTTOM")
		(9 "F.Adhes" user "F.Adhesive")
		(11 "B.Adhes" user "B.Adhesive")
		(13 "F.Paste" user "Package Geometry/Pastemask Top")
		(15 "B.Paste" user "Package Geometry/Pastemask Bottom")
		(5 "F.SilkS" user "Ref Des/Silkscreen Top")
		(7 "B.SilkS" user "Ref Des/Silkscreen Bottom")
		(1 "F.Mask" user "Board Geometry/Soldermask Top")
		(3 "B.Mask" user "Board Geometry/Soldermask Bottom")
		(17 "Dwgs.User" user "User.Drawings")
		(19 "Cmts.User" user "User.Comments")
		(21 "Eco1.User" user "User.Eco1")
		(23 "Eco2.User" user "User.Eco2")
		(25 "Edge.Cuts" user "Board Geometry/Outline")
		(27 "Margin" user)
		(31 "F.CrtYd" user "Package Geometry/Place Bound Top")
		(29 "B.CrtYd" user "Package Geometry/Place Bound Bottom")
		(35 "F.Fab" user "Ref Des/Assembly Top")
		(33 "B.Fab" user "Ref Des/Assembly Bottom")
	)
	(footprint ""
		(layer "F.Cu")
		(at 280.761948 -258.091686)
		(property "Reference" "J6"
			(at -3.683 -81.702148 0)
			(unlocked yes)
			(layer "F.SilkS")
			(effects
				(font
					(size 0.7874 0.5842)
					(thickness 0.1524)
				)
				(justify left)
			)
		)
		(property "Value" ""
			(at 0 0 0)
			(layer "F.Fab")
			(effects
				(font
					(size 1.27 1.27)
				)
			)
		)
		(duplicate_pad_numbers_are_jumpers no)
		(pad "92" smd rect
			(at -2.050034 19.12493 270)
			(size 0.519938 1.4986)
			(layers "F.Cu" "F.Mask" "F.Paste")
			(net "GND")
		)
		(pad "93" smd rect
			(at -2.050034 19.975068 270)
			(size 0.519938 1.4986)
			(layers "F.Cu" "F.Mask" "F.Paste")
			(net "M_C_CPU0_SB_DQS_DP<9>")
		)
		(pad "94" smd rect
			(at -2.050034 20.824952 270)
			(size 0.519938 1.4986)
			(layers "F.Cu" "F.Mask" "F.Paste")
			(net "M_C_CPU0_SB_DQS_DN<9>")
		)
		(pad "95" smd rect
			(at -2.050034 21.67509 270)
			(size 0.519938 1.4986)
			(layers "F.Cu" "F.Mask" "F.Paste")
			(net "GND")
		)
		(pad "96" smd rect
			(at -2.050034 22.524974 270)
			(size 0.519938 1.4986)
			(layers "F.Cu" "F.Mask" "F.Paste")
			(net "M_C_CPU0_SB_CB<0>")
		)
		(pad "97" smd rect
			(at -2.050034 23.375112 270)
			(size 0.519938 1.4986)
			(layers "F.Cu" "F.Mask" "F.Paste")
			(net "GND")
		)
		(pad "98" smd rect
			(at -2.050034 24.224996 270)
			(size 0.519938 1.4986)
			(layers "F.Cu" "F.Mask" "F.Paste")
			(net "M_C_CPU0_SB_CB<1>")
		)
		(pad "99" smd rect
			(at -2.050034 25.07488 270)
			(size 0.519938 1.4986)
			(layers "F.Cu" "F.Mask" "F.Paste")
			(net "GND")
		)
		(pad "100" smd rect
			(at -2.050034 25.925018 270)
			(size 0.519938 1.4986)
			(layers "F.Cu" "F.Mask" "F.Paste")
			(net "M_C_CPU0_SB_DQ<0>")
		)
		(pad "101" smd rect
			(at -2.050034 26.774902 270)
			(size 0.519938 1.4986)
			(layers "F.Cu" "F.Mask" "F.Paste")
			(net "GND")
		)
		(pad "102" smd rect
			(at -2.050034 27.62504 270)
			(size 0.519938 1.4986)
			(layers "F.Cu" "F.Mask" "F.Paste")
			(net "M_C_CPU0_SB_DQ<1>")
		)
		(pad "103" smd rect
			(at -2.050034 28.474924 270)
			(size 0.519938 1.4986)
			(layers "F.Cu" "F.Mask" "F.Paste")
			(net "GND")
		)
		(pad "104" smd rect
			(at -2.050034 29.325062 270)
			(size 0.519938 1.4986)
			(layers "F.Cu" "F.Mask" "F.Paste")
			(net "M_C_CPU0_SB_DQS_DP<0>")
		)
		(pad "105" smd rect
			(at -2.050034 30.174946 270)
			(size 0.519938 1.4986)
			(layers "F.Cu" "F.Mask" "F.Paste")
			(net "M_C_CPU0_SB_DQS_DN<0>")
		)
		(pad "106" smd rect
			(at -2.050034 31.025084 270)
			(size 0.519938 1.4986)
			(layers "F.Cu" "F.Mask" "F.Paste")
			(net "GND")
		)
		(pad "107" smd rect
			(at -2.050034 31.874968 270)
			(size 0.519938 1.4986)
			(layers "F.Cu" "F.Mask" "F.Paste")
			(net "M_C_CPU0_SB_DQ<4>")
		)
		(pad "108" smd rect
			(at -2.050034 32.725106 270)
			(size 0.519938 1.4986)
			(layers "F.Cu" "F.Mask" "F.Paste")
			(net "GND")
		)
		(pad "109" smd rect
			(at -2.050034 33.57499 270)
			(size 0.519938 1.4986)
			(layers "F.Cu" "F.Mask" "F.Paste")
			(net "M_C_CPU0_SB_DQ<5>")
		)
		(pad "110" smd rect
			(at -2.050034 34.425128 270)
			(size 0.519938 1.4986)
			(layers "F.Cu" "F.Mask" "F.Paste")
			(net "GND")
		)
		(pad "111" smd rect
			(at -2.050034 35.275012 270)
			(size 0.519938 1.4986)
			(layers "F.Cu" "F.Mask" "F.Paste")
			(net "M_C_CPU0_SB_DQ<8>")
		)
		(pad "112" smd rect
			(at -2.050034 36.124896 270)
			(size 0.519938 1.4986)
			(layers "F.Cu" "F.Mask" "F.Paste")
			(net "GND")
		)
		(pad "113" smd rect
			(at -2.050034 36.975034 270)
			(size 0.519938 1.4986)
			(layers "F.Cu" "F.Mask" "F.Paste")
			(net "M_C_CPU0_SB_DQ<9>")
		)
		(pad "114" smd rect
			(at -2.050034 37.824918 270)
			(size 0.519938 1.4986)
			(layers "F.Cu" "F.Mask" "F.Paste")
			(net "GND")
		)
		(pad "115" smd rect
			(at -2.050034 38.675056 270)
			(size 0.519938 1.4986)
			(layers "F.Cu" "F.Mask" "F.Paste")
			(net "M_C_CPU0_SB_DQS_DP<1>")
		)
		(pad "116" smd rect
			(at -2.050034 39.52494 270)
			(size 0.519938 1.4986)
			(layers "F.Cu" "F.Mask" "F.Paste")
			(net "M_C_CPU0_SB_DQS_DN<1>")
		)
		(pad "117" smd rect
			(at -2.050034 40.375078 270)
			(size 0.519938 1.4986)
			(layers "F.Cu" "F.Mask" "F.Paste")
			(net "GND")
		)
		(pad "118" smd rect
			(at -2.050034 41.224962 270)
			(size 0.519938 1.4986)
			(layers "F.Cu" "F.Mask" "F.Paste")
			(net "M_C_CPU0_SB_DQ<12>")
		)
		(pad "119" smd rect
			(at -2.050034 42.0751 270)
			(size 0.519938 1.4986)
			(layers "F.Cu" "F.Mask" "F.Paste")
			(net "GND")
		)
		(pad "120" smd rect
			(at -2.050034 42.924984 270)
			(size 0.519938 1.4986)
			(layers "F.Cu" "F.Mask" "F.Paste")
			(net "M_C_CPU0_SB_DQ<13>")
		)
		(pad "121" smd rect
			(at -2.050034 43.775122 270)
			(size 0.519938 1.4986)
			(layers "F.Cu" "F.Mask" "F.Paste")
			(net "GND")
		)
		(pad "122" smd rect
			(at -2.050034 44.625006 270)
			(size 0.519938 1.4986)
			(layers "F.Cu" "F.Mask" "F.Paste")
			(net "M_C_CPU0_SB_DQ<16>")
		)
		(pad "123" smd rect
			(at -2.050034 45.47489 270)
			(size 0.519938 1.4986)
			(layers "F.Cu" "F.Mask" "F.Paste")
			(net "GND")
		)
		(pad "124" smd rect
			(at -2.050034 46.325028 270)
			(size 0.519938 1.4986)
			(layers "F.Cu" "F.Mask" "F.Paste")
			(net "M_C_CPU0_SB_DQ<17>")
		)
		(pad "125" smd rect
			(at -2.050034 47.174912 270)
			(size 0.519938 1.4986)
			(layers "F.Cu" "F.Mask" "F.Paste")
			(net "GND")
		)
		(pad "126" smd rect
			(at -2.050034 48.02505 270)
			(size 0.519938 1.4986)
			(layers "F.Cu" "F.Mask" "F.Paste")
			(net "M_C_CPU0_SB_DQS_DP<2>")
		)
		(pad "127" smd rect
			(at -2.050034 48.874934 270)
			(size 0.519938 1.4986)
			(layers "F.Cu" "F.Mask" "F.Paste")
			(net "M_C_CPU0_SB_DQS_DN<2>")
		)
		(pad "128" smd rect
			(at -2.050034 49.725072 270)
			(size 0.519938 1.4986)
			(layers "F.Cu" "F.Mask" "F.Paste")
			(net "GND")
		)
		(pad "129" smd rect
			(at -2.050034 50.574956 270)
			(size 0.519938 1.4986)
			(layers "F.Cu" "F.Mask" "F.Paste")
			(net "M_C_CPU0_SB_DQ<20>")
		)
		(pad "130" smd rect
			(at -2.050034 51.425094 270)
			(size 0.519938 1.4986)
			(layers "F.Cu" "F.Mask" "F.Paste")
			(net "GND")
		)
		(pad "131" smd rect
			(at -2.050034 52.274978 270)
			(size 0.519938 1.4986)
			(layers "F.Cu" "F.Mask" "F.Paste")
			(net "M_C_CPU0_SB_DQ<21>")
		)
		(pad "132" smd rect
			(at -2.050034 53.125116 270)
			(size 0.519938 1.4986)
			(layers "F.Cu" "F.Mask" "F.Paste")
			(net "GND")
		)
		(pad "133" smd rect
			(at -2.050034 53.975 270)
			(size 0.519938 1.4986)
			(layers "F.Cu" "F.Mask" "F.Paste")
			(net "M_C_CPU0_SB_DQ<24>")
		)
		(pad "134" smd rect
			(at -2.050034 54.824884 270)
			(size 0.519938 1.4986)
			(layers "F.Cu" "F.Mask" "F.Paste")
			(net "GND")
		)
		(pad "135" smd rect
			(at -2.050034 55.675022 270)
			(size 0.519938 1.4986)
			(layers "F.Cu" "F.Mask" "F.Paste")
			(net "M_C_CPU0_SB_DQ<25>")
		)
		(pad "136" smd rect
			(at -2.050034 56.524906 270)
			(size 0.519938 1.4986)
			(layers "F.Cu" "F.Mask" "F.Paste")
			(net "GND")
		)
		(pad "137" smd rect
			(at -2.050034 57.375044 270)
			(size 0.519938 1.4986)
			(layers "F.Cu" "F.Mask" "F.Paste")
			(net "M_C_CPU0_SB_DQS_DP<3>")
		)
	)
)
